#ISCELL
  pure_quanta quanta_title_block_c *
  *
#ISCELL
  pure_quanta_power cad_note *
  *
#ISCELL
  standard offpage *
  page150_i10
#ISCELL
  standard offpage *
  page150_i11
#ISCELL
  standard offpage *
  page150_i12
#ISCELL
  pure_quanta_power gnd *
  page150_i13
#CELL
  pure_quanta q_cap *
  page150_i14
#ISCELL
  pure_quanta_power universal_power *
  page150_i15
#ISCELL
  pure_quanta_power gnd *
  page150_i16
#ISCELL
  pure_quanta_power gnd *
  page150_i17
#ISCELL
  pure_quanta_power universal_power *
  page150_i18
#CELL
  pure_quanta q_cap *
  page150_i19
#ISCELL
  standard offpage *
  page150_i20
#ISCELL
  standard offpage *
  page150_i21
#ISCELL
  standard offpage *
  page150_i22
#ISCELL
  standard offpage *
  page150_i23
#CELL
  pure_quanta q_res *
  page150_i24
#CELL
  pure_quanta q_res *
  page150_i25
#CELL
  pure_quanta q_res *
  page150_i26
#CELL
  pure_quanta q_res *
  page150_i27
#CELL
  pure_quanta sn74avc4t774pwr *
  page150_i28
#ISCELL
  standard offpage *
  page150_i29
#ISCELL
  standard offpage *
  page150_i30
#ISCELL
  standard offpage *
  page150_i31
#ISCELL
  standard offpage *
  page150_i32
#CELL
  pure_quanta q_res *
  page150_i33
#CELL
  pure_quanta q_res *
  page150_i34
#CELL
  pure_quanta q_res *
  page150_i35
#CELL
  pure_quanta q_res *
  page150_i36
#ISCELL
  pure_quanta_power universal_power *
  page150_i37
#ISCELL
  pure_quanta_power universal_power *
  page150_i38
#ISCELL
  pure_quanta_power gnd *
  page150_i39
#CELL
  pure_quanta q_cap *
  page150_i40
#ISCELL
  pure_quanta_power gnd *
  page150_i41
#ISCELL
  pure_quanta_power gnd *
  page150_i42
#CELL
  pure_quanta q_cap *
  page150_i43
#CELL
  pure_quanta sn74avc2t245rswr *
  page150_i60
#ISCELL
  standard offpage *
  page150_i61
#ISCELL
  standard offpage *
  page150_i62
#ISCELL
  pure_quanta_power gnd *
  page150_i63
#ISCELL
  pure_quanta_power universal_power *
  page150_i64
#ISCELL
  pure_quanta_power gnd *
  page150_i65
#CELL
  pure_quanta q_cap *
  page150_i66
#ISCELL
  pure_quanta_power universal_power *
  page150_i67
#ISCELL
  pure_quanta_power gnd *
  page150_i68
#CELL
  pure_quanta q_cap *
  page150_i69
#ISCELL
  pure_quanta_power gnd *
  page150_i70
#CELL
  pure_quanta q_res *
  page150_i71
#ISCELL
  standard offpage *
  page150_i72
#ISCELL
  standard offpage *
  page150_i73
#ISCELL
  standard offpage *
  page150_i74
#ISCELL
  standard offpage *
  page150_i75
#CELL
  pure_quanta q_res *
  page150_i76
#CELL
  pure_quanta q_res *
  page150_i78
#CELL
  pure_quanta sn74avc4t774pwr *
  page150_i8
#ISCELL
  standard offpage *
  page150_i9
